FILE_TYPE = CONNECTIVITY;
{Allegro Design Entry HDL 17.4-2019 S026 (4007227) 1/17/2022}
"PAGE_NUMBER" = 401;
0"NC";
1"P1V8_CPU1_RT_1D\g";
2"GND\g";
3"GND\g";
4"GND\g";
5"P1V8_CPU1_RT_1D\g";
6"GND\g";
7"GND\g";
8"GND\g";
9"P1V8_CPU1_RT_1D\g";
10"GND\g";
11"GND\g";
12"P1V8_CPU1_RT_1D\g";
13"GND\g";
14"GND\g";
15"GND\g";
16"SMB_RT_CPU1_P0_ROM_MUX_1D_SCL";
17"P1V8_CPU1_RT_1D\g";
18"P1V8_CPU1_RT_1D\g";
19"GND\g";
20"GND\g";
21"P1V8_CPU1_RT_1D\g";
22"SMB_RT_CPU1_P0_ROM_MUX_1D_R_SCL";
23"SMB_RT_CPU1_P0_ROM_MUX_1D_R_SDA";
24"SMB_RT_CPU1_P0_ROM_MUX_1D_SDA";
25"RT_CPU1_P0_SCAN_MODE";
26"JTAG_TDI_RT_CPU1_P0";
27"JTAG_TMS_RT_CPU1_P0";
28"JTAG_TDO_RT_CPU1_P0";
29"JTAG_TCK_RT_CPU1_P0";
30"RST_RT_CPU1_P0_PERST_N";
31"CLKREQ_RT_CPU1_P0_N";
32"RT_CPU1_P0_SCAN_MODE";
33"RXDET_BYP_RT_CPU1_P0";
34"MODE_RT_CPU1_P0";
35"JTAG_TDI_RT_CPU1_P0";
36"JTAG_TMS_RT_CPU1_P0";
37"JTAG_TDO_RT_CPU1_P0";
38"JTAG_TCK_RT_CPU1_P0";
39"JTAG_TRST_RT_CPU1_P0_N";
40"RST_RT_CPU1_P0_RESET_R_N";
41"RST_RT_CPU1_P0_PERST_R_N";
42"JTAG_TEST_MODE_RT_CPU1_P0";
43"RXDET_BYP_RT_CPU1_P0";
44"RST_RT_CPU1_P0_RESET_N";
45"GPIO3_RT_CPU1_P0";
46"RST_RT_CPU1_P0_RESET_R_N";
47"CLK_100M_RETIMER_CPU1_P0_R_DP";
48"GPIO3_RT_CPU1_P0";
49"SMB_RT_CPU1_P0_R2_SDA";
50"RT_CPU1_P0_ADDR3";
51"RT_CPU1_P0_ADDR2";
52"RT_CPU1_P0_ADDR1";
53"MODE_RT_CPU1_P0";
54"CLK_100M_RETIMER_CPU1_P0_DP";
55"CLK_100M_RETIMER_CPU1_P0_DN";
56"RT_CPU1_P0_ADDR3";
57"SMB_RT_CPU1_P0_R2_SCL";
58"TEST2_RT_CPU1_P0";
59"JTAG_TEST_MODE_RT_CPU1_P0";
60"RT_CPU1_P0_ADDR2";
61"GPIO2_RT_CPU1_P0";
62"TEST0_RT_CPU1_P0";
63"RST_RT_CPU1_P0_PERST_R_N";
64"TEST1_RT_CPU1_P0";
65"SMB_RT_CPU1_P0_R_SCL";
66"TEST2_RT_CPU1_P0";
67"TEST1_RT_CPU1_P0";
68"TEST0_RT_CPU1_P0";
69"RT_CPU1_P0_ADDR1";
70"SMB_RT_CPU1_P0_R_SDA";
71"CLK_100M_RETIMER_CPU1_P0_R_DN";
72"GPIO2_RT_CPU1_P0";
%"PT5161LRS"
"3","(-4375,2450)","0","pure_quanta","I1";
;
LOCATION"U6014"
$SEC"3"
CDS_SEC"3"
PART_TYPE"SMLF"
VALUE"PT5161LRS"
MATERIAL"IC"
NEEDS_NO_SIZE"TRUE"
CDS_LMAN_SYM_OUTLINE"-500,1450,450,-1400"
CDS_LIB"pure_quanta"
PART_NUMBER"AJ051610U03";
"EE_DAT"
$PN"FJ3"23;
"EE_CLK"
$PN"FF5"22;
"CLKREQ_N \B"
$PN"G35"31;
"TEST2"
$PN"FF30"66;
"TEST1"
$PN"FF27"67;
"TEST0"
$PN"FF24"68;
"T_SENSE"
$PN"E30"13;
"SMBDAT"
$PN"B28"49;
"SMBCLK"
$PN"B31"57;
"SMB_ADDR3"
$PN"B25"56;
"SMB_ADDR2"
$PN"B23"60;
"SMB_ADDR1"
$PN"F34"69;
"SCAN_MODE"
$PN"FF33"32;
"RXDET_BYP"
$PN"E11"33;
"RESET_N \B"
$PN"FF11"44;
"REFCLKP"
$PN"FJ16"54;
"REFCLKN"
$PN"FF18"55;
"REFCLK_OUTP"
$PN"B16"0;
"REFCLK_OUTN"
$PN"E18"0;
"PERST_N \B"
$PN"F2"30;
"MODE"
$PN"FJ9"34;
"JTAG_TRST_N \B"
$PN"E8"39;
"JTAG_TMS"
$PN"B12"36;
"JTAG_TEST_MODE"
$PN"FF8"42;
"JTAG_TDO"
$PN"B9"37;
"JTAG_TDI"
$PN"B6"35;
"JTAG_TCK"
$PN"B3"38;
"INT_N \B"
$PN"FJ31"0;
"GPIO3"
$PN"FJ28"45;
"GPIO2"
$PN"FJ25"72;
"GPIO1"
$PN"FJ23"0;
"GPIO0"
$PN"FJ6"0;
%"P1V0"
"1","(-1475,6400)","0","pure_quanta_power","I100";
;
HDL_POWER"P1V8_CPU1_RT_1D"
CDS_LIB"pure_quanta_power";
"A"1;
%"Q_RES"
"2","(-1475,6150)","2","pure_quanta","I101";
;
LOCATION"R6724"
$SEC"1"
CDS_SEC"1"
VALUE"4.7K"
TOLERANCE"5%"
WATTAGE"1/20W"
MATERIAL"EMPTY"
PACK_TYPE"0201LF"
CDS_LIB"pure_quanta"
PART_NUMBER"CS24701JE04";
"A"
$PN"1"1;
"B"
$PN"2"46;
%"Q_RES"
"2","(-3475,6100)","0","pure_quanta","I102";
;
LOCATION"R6712"
$SEC"1"
CDS_SEC"1"
PACK_TYPE"0201LF"
MATERIAL"CHIP"
TOLERANCE"1%"
WATTAGE"1/20W"
VALUE"1K"
CDS_LIB"pure_quanta"
PART_NUMBER"CS21001FE07";
"A"
$PN"1"21;
"B"
$PN"2"50;
%"Q_RES"
"2","(-3475,5325)","0","pure_quanta","I103";
;
LOCATION"R6713"
$SEC"1"
CDS_SEC"1"
PACK_TYPE"0201LF"
VALUE"1K"
TOLERANCE"1%"
MATERIAL"EMPTY"
WATTAGE"1/20W"
CDS_LIB"pure_quanta"
PART_NUMBER"CS21001FE07";
"A"
$PN"1"50;
"B"
$PN"2"20;
%"Q_RES"
"2","(-3175,6100)","0","pure_quanta","I104";
;
LOCATION"R6714"
$SEC"1"
CDS_SEC"1"
PACK_TYPE"0201LF"
VALUE"1K"
WATTAGE"1/20W"
MATERIAL"EMPTY"
TOLERANCE"1%"
CDS_LIB"pure_quanta"
PART_NUMBER"CS21001FE07";
"A"
$PN"1"21;
"B"
$PN"2"51;
%"Q_RES"
"2","(-3175,5325)","0","pure_quanta","I105";
;
LOCATION"R6715"
$SEC"1"
CDS_SEC"1"
MATERIAL"CHIP"
VALUE"20K"
TOLERANCE"1%"
WATTAGE"1/20W"
PACK_TYPE"0201LF"
CDS_LIB"pure_quanta"
PART_NUMBER"CS32001FE00";
"A"
$PN"1"51;
"B"
$PN"2"20;
%"Q_RES"
"2","(-2825,5325)","0","pure_quanta","I106";
;
LOCATION"R6717"
$SEC"1"
CDS_SEC"1"
VALUE"1K"
TOLERANCE"1%"
MATERIAL"CHIP"
WATTAGE"1/20W"
PACK_TYPE"0201LF"
CDS_LIB"pure_quanta"
PART_NUMBER"CS21001FE07";
"A"
$PN"1"52;
"B"
$PN"2"20;
%"Q_RES"
"2","(-2825,6075)","0","pure_quanta","I107";
;
LOCATION"R6716"
$SEC"1"
CDS_SEC"1"
MATERIAL"EMPTY"
PACK_TYPE"0201LF"
TOLERANCE"1%"
WATTAGE"1/20W"
VALUE"1K"
CDS_LIB"pure_quanta"
PART_NUMBER"CS21001FE07";
"A"
$PN"1"21;
"B"
$PN"2"52;
%"Q_RES"
"1","(-2675,2400)","0","pure_quanta","I108";
;
LOCATION"R1387"
$SEC"1"
CDS_SEC"1"
VALUE"4.7K"
PACK_TYPE"0201LF"
MATERIAL"CHIP"
WATTAGE"1/20W"
TOLERANCE"5%"
CDS_LIB"pure_quanta"
PART_NUMBER"CS24701JE04";
"B"
$PN"2"2;
"A"
$PN"1"31;
%"Q_RES"
"1","(-2700,3350)","0","pure_quanta","I112";
;
LOCATION"R1380"
$SEC"1"
CDS_SEC"1"
MATERIAL"CHIP"
PACK_TYPE"0201LF"
VALUE"1K"
CDS_LIB"pure_quanta"
WATTAGE"1/20W"
TOLERANCE"1%"
PART_NUMBER"CS21001FE07";
"B"
$PN"2"4;
"A"
$PN"1"39;
%"UNIVERSAL_GND"
"1","(-1950,2400)","1","pure_quanta_power","I117";
;
CDS_LIB"pure_quanta_power"
HDL_POWER"GND";
"A"2;
%"GND"
"1","(-1525,3100)","0","pure_quanta_power","I118";
;
BOM_COST"MEM"
SIZE"1B"
CDS_LIB"pure_quanta_power"
HDL_POWER"GND";
"A<SIZE-1..0>\NAC"3;
%"UNIVERSAL_GND"
"1","(-1950,3350)","1","pure_quanta_power","I119";
;
CDS_LIB"pure_quanta_power"
HDL_POWER"GND";
"A"4;
%"Q_RES"
"2","(-1525,3500)","0","pure_quanta","I124";
;
LOCATION"R1389"
$SEC"1"
CDS_SEC"1"
TOLERANCE"1%"
VALUE"10K"
WATTAGE"1/20W"
PACK_TYPE"0201LF"
MATERIAL"CHIP"
CDS_LIB"pure_quanta"
PART_NUMBER"CS31001FE17";
"A"
$PN"1"43;
"B"
$PN"2"3;
%"Q_RES"
"2","(-1525,4025)","0","pure_quanta","I125";
;
LOCATION"R1388"
$SEC"1"
CDS_SEC"1"
PACK_TYPE"0201LF"
TOLERANCE"1%"
WATTAGE"1/20W"
MATERIAL"EMPTY"
VALUE"1K"
CDS_LIB"pure_quanta"
PART_NUMBER"CS21001FE07";
"A"
$PN"1"5;
"B"
$PN"2"43;
%"P1V0"
"1","(-1525,4425)","0","pure_quanta_power","I127";
;
HDL_POWER"P1V8_CPU1_RT_1D"
CDS_LIB"pure_quanta_power";
"A"5;
%"Q_RES"
"2","(-8975,3550)","0","pure_quanta","I128";
;
LOCATION"R6723"
$SEC"1"
CDS_SEC"1"
VALUE"200"
PACK_TYPE"0201LF"
WATTAGE"1/20W"
TOLERANCE"1%"
MATERIAL"CHIP"
CDS_LIB"pure_quanta"
PART_NUMBER"CS12001FE12";
"A"
$PN"1"25;
"B"
$PN"2"11;
%"Q_RES"
"1","(-6325,1650)","0","pure_quanta","I13";
;
LOCATION"R675"
$SEC"1"
CDS_SEC"1"
MATERIAL"CHIP"
TOLERANCE"1%"
WATTAGE"1/20W"
VALUE"49.9"
PACK_TYPE"0201LF"
CDS_LIB"pure_quanta"
PART_NUMBER"CS04991FE06";
"B"
$PN"2"23;
"A"
$PN"1"24;
%"GND"
"1","(-650,450)","0","pure_quanta_power","I143";
;
SIZE"1B"
BOM_COST"MEM"
CDS_LIB"pure_quanta_power"
HDL_POWER"GND";
"A<SIZE-1..0>\NAC"6;
%"Q_RES"
"2","(-650,750)","0","pure_quanta","I144";
;
LOCATION"R1381"
$SEC"1"
CDS_SEC"1"
WATTAGE"1/20W"
TOLERANCE"5%"
VALUE"4.7K"
PACK_TYPE"0201LF"
MATERIAL"CHIP"
CDS_LIB"pure_quanta"
PART_NUMBER"CS24701JE04";
"A"
$PN"1"29;
"B"
$PN"2"6;
%"Q_RES"
"2","(-1200,1375)","0","pure_quanta","I145";
;
LOCATION"R1465"
$SEC"1"
CDS_SEC"1"
TOLERANCE"5%"
VALUE"4.7K"
WATTAGE"1/20W"
MATERIAL"EMPTY"
PACK_TYPE"0201LF"
CDS_LIB"pure_quanta"
PART_NUMBER"CS24701JE04";
"A"
$PN"1"17;
"B"
$PN"2"27;
%"Q_RES"
"2","(-925,1375)","0","pure_quanta","I146";
;
LOCATION"R1466"
$SEC"1"
CDS_SEC"1"
VALUE"1K"
TOLERANCE"1%"
WATTAGE"1/20W"
MATERIAL"EMPTY"
PACK_TYPE"0201LF"
CDS_LIB"pure_quanta"
PART_NUMBER"CS21001FE07";
"A"
$PN"1"17;
"B"
$PN"2"28;
%"Q_RES"
"2","(-650,1400)","0","pure_quanta","I147";
;
LOCATION"R1467"
$SEC"1"
CDS_SEC"1"
TOLERANCE"5%"
VALUE"4.7K"
WATTAGE"1/20W"
MATERIAL"EMPTY"
PACK_TYPE"0201LF"
CDS_LIB"pure_quanta"
PART_NUMBER"CS24701JE04";
"A"
$PN"1"17;
"B"
$PN"2"29;
%"P1V0"
"1","(-650,1700)","0","pure_quanta_power","I148";
;
HDL_POWER"P1V8_CPU1_RT_1D"
CDS_LIB"pure_quanta_power";
"A"17;
%"Q_RES"
"2","(-1475,1375)","0","pure_quanta","I149";
;
LOCATION"R1464"
$SEC"1"
CDS_SEC"1"
TOLERANCE"5%"
VALUE"4.7K"
WATTAGE"1/20W"
MATERIAL"EMPTY"
PACK_TYPE"0201LF"
CDS_LIB"pure_quanta"
PART_NUMBER"CS24701JE04";
"A"
$PN"1"17;
"B"
$PN"2"26;
%"Q_RES"
"1","(-6325,1750)","0","pure_quanta","I155";
;
LOCATION"R674"
SEC"1"
MATERIAL"CHIP"
PACK_TYPE"0201LF"
WATTAGE"1/20W"
TOLERANCE"1%"
VALUE"22"
SEC_TYPE"0201LF"
CDS_LIB"pure_quanta"
PART_NUMBER"CS02201FE11";
"B"
$PN"2"22;
"A"
$PN"1"16;
%"Q_RES"
"1","(-6350,3000)","0","pure_quanta","I19";
;
LOCATION"R6812"
$SEC"1"
CDS_SEC"1"
MATERIAL"CHIP"
VALUE"0"
TOLERANCE"5%"
PACK_TYPE"0201LF"
WATTAGE"1/20W"
CDS_LIB"pure_quanta"
PART_NUMBER"CS00001JE10";
"B"
$PN"2"57;
"A"
$PN"1"65;
%"Q_RES"
"1","(-6350,2900)","0","pure_quanta","I20";
;
LOCATION"R6813"
$SEC"1"
CDS_SEC"1"
CDS_LIB"pure_quanta"
PACK_TYPE"0201LF"
MATERIAL"CHIP"
TOLERANCE"5%"
VALUE"0"
WATTAGE"1/20W"
PART_NUMBER"CS00001JE10";
"B"
$PN"2"49;
"A"
$PN"1"70;
%"Q_RES"
"2","(-6300,825)","2","pure_quanta","I23";
;
LOCATION"R627"
$SEC"1"
CDS_SEC"1"
TOLERANCE"1%"
MATERIAL"EMPTY"
PACK_TYPE"0201LF"
WATTAGE"1/20W"
VALUE"51.1"
CDS_LIB"pure_quanta"
PART_NUMBER"CS05111FE00";
"A"
$PN"1"55;
"B"
$PN"2"8;
%"Q_RES"
"2","(-6150,825)","0","pure_quanta","I24";
;
LOCATION"R628"
$SEC"1"
CDS_SEC"1"
PACK_TYPE"0201LF"
TOLERANCE"1%"
MATERIAL"EMPTY"
WATTAGE"1/20W"
VALUE"51.1"
CDS_LIB"pure_quanta"
PART_NUMBER"CS05111FE00";
"A"
$PN"1"54;
"B"
$PN"2"7;
%"Q_RES"
"2","(-7725,6075)","0","pure_quanta","I25";
;
LOCATION"R724"
$SEC"1"
CDS_SEC"1"
TOLERANCE"5%"
VALUE"4.7K"
MATERIAL"EMPTY"
PACK_TYPE"0201LF"
WATTAGE"1/20W"
CDS_LIB"pure_quanta"
PART_NUMBER"CS24701JE04";
"A"
$PN"1"18;
"B"
$PN"2"58;
%"Q_RES"
"2","(-8025,6050)","0","pure_quanta","I26";
;
LOCATION"R720"
$SEC"1"
CDS_SEC"1"
WATTAGE"1/20W"
TOLERANCE"5%"
VALUE"4.7K"
PACK_TYPE"0201LF"
MATERIAL"EMPTY"
CDS_LIB"pure_quanta"
PART_NUMBER"CS24701JE04";
"A"
$PN"1"18;
"B"
$PN"2"64;
%"Q_RES"
"2","(-8325,6100)","0","pure_quanta","I27";
;
LOCATION"R716"
$SEC"1"
CDS_SEC"1"
TOLERANCE"5%"
PACK_TYPE"0201LF"
MATERIAL"EMPTY"
WATTAGE"1/20W"
VALUE"4.7K"
CDS_LIB"pure_quanta"
PART_NUMBER"CS24701JE04";
"A"
$PN"1"18;
"B"
$PN"2"62;
%"Q_RES"
"2","(-8950,6100)","0","pure_quanta","I29";
;
LOCATION"R706"
$SEC"1"
CDS_SEC"1"
TOLERANCE"5%"
VALUE"4.7K"
WATTAGE"1/20W"
MATERIAL"EMPTY"
PACK_TYPE"0201LF"
CDS_LIB"pure_quanta"
PART_NUMBER"CS24701JE04";
"A"
$PN"1"18;
"B"
$PN"2"61;
%"Q_RES"
"2","(-7725,5125)","0","pure_quanta","I32";
;
LOCATION"R725"
$SEC"1"
CDS_SEC"1"
TOLERANCE"5%"
PACK_TYPE"0201LF"
VALUE"4.7K"
WATTAGE"1/20W"
MATERIAL"CHIP"
CDS_LIB"pure_quanta"
PART_NUMBER"CS24701JE04";
"A"
$PN"1"58;
"B"
$PN"2"19;
%"Q_RES"
"2","(-8025,5125)","0","pure_quanta","I33";
;
LOCATION"R723"
$SEC"1"
CDS_SEC"1"
TOLERANCE"5%"
PACK_TYPE"0201LF"
MATERIAL"CHIP"
WATTAGE"1/20W"
VALUE"4.7K"
CDS_LIB"pure_quanta"
PART_NUMBER"CS24701JE04";
"A"
$PN"1"64;
"B"
$PN"2"19;
%"Q_RES"
"2","(-8325,5150)","0","pure_quanta","I34";
;
LOCATION"R719"
$SEC"1"
CDS_SEC"1"
VALUE"4.7K"
TOLERANCE"5%"
WATTAGE"1/20W"
PACK_TYPE"0201LF"
MATERIAL"CHIP"
CDS_LIB"pure_quanta"
PART_NUMBER"CS24701JE04";
"A"
$PN"1"62;
"B"
$PN"2"19;
%"Q_RES"
"2","(-8650,5150)","0","pure_quanta","I35";
;
LOCATION"R715"
$SEC"1"
CDS_SEC"1"
VALUE"10K"
TOLERANCE"1%"
WATTAGE"1/20W"
MATERIAL"CHIP"
PACK_TYPE"0201LF"
CDS_LIB"pure_quanta"
PART_NUMBER"CS31001FE17";
"A"
$PN"1"48;
"B"
$PN"2"19;
%"Q_RES"
"2","(-8950,5150)","0","pure_quanta","I36";
;
LOCATION"R707"
$SEC"1"
CDS_SEC"1"
VALUE"10K"
TOLERANCE"1%"
WATTAGE"1/20W"
MATERIAL"CHIP"
PACK_TYPE"0201LF"
CDS_LIB"pure_quanta"
PART_NUMBER"CS31001FE17";
"A"
$PN"1"61;
"B"
$PN"2"19;
%"P1V0"
"1","(-8950,6500)","0","pure_quanta_power","I39";
;
HDL_POWER"P1V8_CPU1_RT_1D"
CDS_LIB"pure_quanta_power";
"A"18;
%"UNIVERSAL_GND"
"1","(-6150,500)","0","pure_quanta_power","I4";
;
CDS_LIB"pure_quanta_power"
HDL_POWER"GND";
"A"7;
%"UNIVERSAL_GND"
"1","(-7425,4650)","0","pure_quanta_power","I40";
;
CDS_LIB"pure_quanta_power"
HDL_POWER"GND";
"A"19;
%"UNIVERSAL_GND"
"1","(-6300,500)","0","pure_quanta_power","I5";
;
CDS_LIB"pure_quanta_power"
HDL_POWER"GND";
"A"8;
%"Q_RES"
"2","(-5025,6175)","0","pure_quanta","I54";
;
LOCATION"R727"
$SEC"1"
CDS_SEC"1"
VALUE"4.7K"
TOLERANCE"5%"
MATERIAL"CHIP"
WATTAGE"1/20W"
PACK_TYPE"0201LF"
CDS_LIB"pure_quanta"
PART_NUMBER"CS24701JE04";
"A"
$PN"1"9;
"B"
$PN"2"53;
%"Q_RES"
"2","(-5025,5650)","0","pure_quanta","I55";
;
LOCATION"R728"
$SEC"1"
CDS_SEC"1"
WATTAGE"1/20W"
TOLERANCE"5%"
VALUE"4.7K"
MATERIAL"EMPTY"
PACK_TYPE"0201LF"
CDS_LIB"pure_quanta"
PART_NUMBER"CS24701JE04";
"A"
$PN"1"53;
"B"
$PN"2"10;
%"P1V0"
"1","(-5025,6500)","0","pure_quanta_power","I56";
;
HDL_POWER"P1V8_CPU1_RT_1D"
CDS_LIB"pure_quanta_power";
"A"9;
%"UNIVERSAL_GND"
"1","(-5025,5300)","0","pure_quanta_power","I57";
;
CDS_LIB"pure_quanta_power"
HDL_POWER"GND";
"A"10;
%"Q_RES"
"1","(-2575,2300)","0","pure_quanta","I62";
;
LOCATION"R6708"
SEC"1"
PACK_TYPE"0201LF"
VALUE"0"
WATTAGE"1/20W"
TOLERANCE"5%"
MATERIAL"CHIP"
SEC_TYPE"0201LF"
CDS_LIB"pure_quanta"
PART_NUMBER"CS00001JE10";
"B"
$PN"2"41;
"A"
$PN"1"30;
%"Q_RES"
"1","(-2575,2200)","0","pure_quanta","I65";
;
LOCATION"R6709"
$SEC"1"
CDS_SEC"1"
PACK_TYPE"0201LF"
VALUE"0"
CDS_LIB"pure_quanta"
MATERIAL"CHIP"
TOLERANCE"5%"
WATTAGE"1/20W"
PART_NUMBER"CS00001JE10";
"B"
$PN"2"40;
"A"
$PN"1"44;
%"UNIVERSAL_GND"
"1","(-3475,4900)","0","pure_quanta_power","I72";
;
CDS_LIB"pure_quanta_power"
HDL_POWER"GND";
"A"20;
%"P1V0"
"1","(-3475,6525)","0","pure_quanta_power","I73";
;
HDL_POWER"P1V8_CPU1_RT_1D"
CDS_LIB"pure_quanta_power";
"A"21;
%"Q_RES"
"1","(-6600,1150)","0","pure_quanta","I8";
;
LOCATION"R609"
SEC"1"
MATERIAL"CHIP"
PACK_TYPE"0201LF"
CDS_LIB"pure_quanta"
TOLERANCE"5%"
VALUE"0"
WATTAGE"1/20W"
SEC_TYPE"0201LF"
PART_NUMBER"CS00001JE10";
"B"
$PN"2"55;
"A"
$PN"1"71;
%"Q_RES"
"2","(-8975,4225)","0","pure_quanta","I85";
;
LOCATION"R6722"
$SEC"1"
CDS_SEC"1"
PACK_TYPE"0201LF"
WATTAGE"1/20W"
MATERIAL"EMPTY"
VALUE"4.7K"
TOLERANCE"5%"
CDS_LIB"pure_quanta"
PART_NUMBER"CS24701JE04";
"A"
$PN"1"12;
"B"
$PN"2"25;
%"UNIVERSAL_GND"
"1","(-8975,3275)","0","pure_quanta_power","I86";
;
CDS_LIB"pure_quanta_power"
HDL_POWER"GND";
"A"11;
%"P1V0"
"1","(-8975,4550)","0","pure_quanta_power","I87";
;
HDL_POWER"P1V8_CPU1_RT_1D"
CDS_LIB"pure_quanta_power";
"A"12;
%"Q_RES"
"1","(-6600,1300)","0","pure_quanta","I9";
;
LOCATION"R599"
SEC"1"
VALUE"0"
TOLERANCE"5%"
WATTAGE"1/20W"
PACK_TYPE"0201LF"
MATERIAL"CHIP"
CDS_LIB"pure_quanta"
SEC_TYPE"0201LF"
PART_NUMBER"CS00001JE10";
"B"
$PN"2"54;
"A"
$PN"1"47;
%"Q_RES"
"2","(-7425,5100)","0","pure_quanta","I90";
;
LOCATION"R726"
$SEC"1"
CDS_SEC"1"
TOLERANCE"5%"
PACK_TYPE"0201LF"
WATTAGE"1/20W"
VALUE"4.7K"
MATERIAL"CHIP"
CDS_LIB"pure_quanta"
PART_NUMBER"CS24701JE04";
"A"
$PN"1"59;
"B"
$PN"2"19;
%"Q_RES"
"2","(-7425,6100)","0","pure_quanta","I91";
;
LOCATION"R6725"
$SEC"1"
CDS_SEC"1"
TOLERANCE"5%"
VALUE"4.7K"
MATERIAL"EMPTY"
WATTAGE"1/20W"
PACK_TYPE"0201LF"
CDS_LIB"pure_quanta"
PART_NUMBER"CS24701JE04";
"A"
$PN"1"18;
"B"
$PN"2"59;
%"UNIVERSAL_GND"
"1","(-2625,1800)","1","pure_quanta_power","I93";
;
CDS_LIB"pure_quanta_power"
HDL_POWER"GND";
"A"13;
%"Q_RES"
"2","(-1475,5325)","2","pure_quanta","I96";
;
LOCATION"R6721"
$SEC"1"
CDS_SEC"1"
TOLERANCE"1%"
MATERIAL"CHIP"
PACK_TYPE"0201LF"
WATTAGE"1/20W"
VALUE"10K"
CDS_LIB"pure_quanta"
PART_NUMBER"CS31001FE17";
"A"
$PN"1"46;
"B"
$PN"2"14;
%"Q_RES"
"2","(-1300,5325)","0","pure_quanta","I97";
;
LOCATION"R6720"
$SEC"1"
CDS_SEC"1"
VALUE"10K"
WATTAGE"1/20W"
MATERIAL"CHIP"
PACK_TYPE"0201LF"
TOLERANCE"1%"
CDS_LIB"pure_quanta"
PART_NUMBER"CS31001FE17";
"A"
$PN"1"63;
"B"
$PN"2"15;
%"GND"
"1","(-1475,4950)","0","pure_quanta_power","I98";
;
BOM_COST"MEM"
SIZE"1B"
CDS_LIB"pure_quanta_power"
HDL_POWER"GND";
"A<SIZE-1..0>\NAC"14;
%"GND"
"1","(-1300,4975)","0","pure_quanta_power","I99";
;
CDS_LIB"pure_quanta_power"
BOM_COST"MEM"
SIZE"1B"
HDL_POWER"GND";
"A<SIZE-1..0>\NAC"15;
END.
